(kicad_pcb
	(version 20241229)
	(generator "pcbnew")
	(generator_version "9.0")
	(general
		(thickness 1.711)
		(legacy_teardrops no)
	)
	(paper "A4")
	(title_block
		(title "Antmicro Baseboard for Jetson AGX Thor")
		(date "2026-02-18")
		(rev "1.1.0")
		(company "Antmicro Ltd")
		(comment 1 "www.antmicro.com")
		(comment 9 "footprints 668-671 of 1170")
	)
	(layers
		(0 "F.Cu" signal)
		(4 "In1.Cu" signal)
		(6 "In2.Cu" signal)
		(8 "In3.Cu" signal)
		(10 "In4.Cu" jumper)
		(12 "In5.Cu" signal)
		(14 "In6.Cu" signal)
		(16 "In7.Cu" signal)
		(18 "In8.Cu" signal)
		(2 "B.Cu" signal)
		(9 "F.Adhes" user "F.Adhesive")
		(11 "B.Adhes" user "B.Adhesive")
		(13 "F.Paste" user)
		(15 "B.Paste" user)
		(5 "F.SilkS" user "F.Silkscreen")
		(7 "B.SilkS" user "B.Silkscreen")
		(1 "F.Mask" user)
		(3 "B.Mask" user)
		(17 "Dwgs.User" user "User.Drawings")
		(19 "Cmts.User" user "User.Comments")
		(21 "Eco1.User" user "User.Eco1")
		(23 "Eco2.User" user "User.Eco2")
		(25 "Edge.Cuts" user)
		(27 "Margin" user)
		(31 "F.CrtYd" user "F.Courtyard")
		(29 "B.CrtYd" user "B.Courtyard")
		(35 "F.Fab" user)
		(33 "B.Fab" user)
	)
	(footprint "antmicro-footprints:R_0603_1608Metric"
		(layer "B.Cu")
		(at 84 140.75)
		(descr "Resistor SMD 0603")
		(tags "resistor SMD 0603")
		(property "Reference" "R247"
			(at -1.6 -1.55 0)
			(layer "B.SilkS")
			(effects
				(font
					(size 0.7 0.7)
					(thickness 0.15)
				)
				(justify right top mirror)
			)
		)
		(property "Value" "R_0R_22.4A_0603"
			(at 0 -1.6 0)
			(layer "B.Fab")
			(effects
				(font
					(size 0.7 0.7)
					(thickness 0.15)
				)
				(justify right top mirror)
			)
		)
		(property "Datasheet" "https://fscdn.rohm.com/en/products/databook/datasheet/passive/resistor/chip_resistor/pmr-jpw-e.pdf"
			(at 0 0 0)
			(layer "B.Fab")
			(hide yes)
			(effects
				(font
					(size 1.27 1.27)
					(thickness 0.15)
				)
				(justify mirror)
			)
		)
		(property "Description" "SMD Chip Resistor"
			(at 0 0 0)
			(layer "B.Fab")
			(hide yes)
			(effects
				(font
					(size 1.27 1.27)
					(thickness 0.15)
				)
				(justify mirror)
			)
		)
		(property "MPN" "PMR03EZPJ000"
			(at 0 0 180)
			(unlocked yes)
			(layer "B.Fab")
			(hide yes)
			(effects
				(font
					(size 1 1)
					(thickness 0.15)
				)
				(justify mirror)
			)
		)
		(property "Manufacturer" "ROHM Semiconductor"
			(at 0 0 180)
			(unlocked yes)
			(layer "B.Fab")
			(hide yes)
			(effects
				(font
					(size 1 1)
					(thickness 0.15)
				)
				(justify mirror)
			)
		)
		(property "Val" "0R"
			(at 0 0 180)
			(unlocked yes)
			(layer "B.Fab")
			(hide yes)
			(effects
				(font
					(size 1 1)
					(thickness 0.15)
				)
				(justify mirror)
			)
		)
		(property "Max. Curr." "22.4A"
			(at 0 0 180)
			(unlocked yes)
			(layer "B.Fab")
			(hide yes)
			(effects
				(font
					(size 1 1)
					(thickness 0.15)
				)
				(justify mirror)
			)
		)
		(property "Author" "Antmicro"
			(at 0 0 180)
			(unlocked yes)
			(layer "B.Fab")
			(hide yes)
			(effects
				(font
					(size 1 1)
					(thickness 0.15)
				)
				(justify mirror)
			)
		)
		(property "License" "Apache-2.0"
			(at 0 0 180)
			(unlocked yes)
			(layer "B.Fab")
			(hide yes)
			(effects
				(font
					(size 1 1)
					(thickness 0.15)
				)
				(justify mirror)
			)
		)
		(property "Tolerance" "template_tolerance"
			(at 0 0 180)
			(unlocked yes)
			(layer "B.Fab")
			(hide yes)
			(effects
				(font
					(size 1 1)
					(thickness 0.15)
				)
				(justify mirror)
			)
		)
		(sheetname "/Expansion connector/")
		(sheetfile "expansion_connector.kicad_sch")
		(attr smd exclude_from_pos_files exclude_from_bom dnp)
		(fp_line
			(start -0.15 -0.4)
			(end 0.15 -0.4)
			(stroke
				(width 0.15)
				(type solid)
			)
			(layer "B.SilkS")
		)
		(fp_line
			(start -0.15 0.4)
			(end 0.15 0.4)
			(stroke
				(width 0.15)
				(type solid)
			)
			(layer "B.SilkS")
		)
		(fp_poly
			(pts
				(xy -1.25 0.65) (xy -1.25 -0.65) (xy 1.25 -0.65) (xy 1.25 0.65)
			)
			(stroke
				(width 0.05)
				(type solid)
			)
			(fill no)
			(layer "B.CrtYd")
		)
		(fp_poly
			(pts
				(xy -0.8 0.4) (xy -0.8 -0.4) (xy 0.8 -0.4) (xy 0.8 0.4)
			)
			(stroke
				(width 0.15)
				(type solid)
			)
			(fill no)
			(layer "B.Fab")
		)
		(fp_text user "Author: Antmicro"
			(at -1.25 -4.9 0)
			(layer "B.Fab")
			(effects
				(font
					(size 0.7 0.7)
					(thickness 0.15)
				)
				(justify right top mirror)
			)
		)
		(fp_text user "License: Apache-2.0"
			(at -1.249999 -5.9 0)
			(layer "B.Fab")
			(effects
				(font
					(size 0.7 0.7)
					(thickness 0.15)
				)
				(justify right top mirror)
			)
		)
		(fp_text user "${REFERENCE}"
			(at -1.25 -3.898 0)
			(layer "B.Fab")
			(effects
				(font
					(size 0.7 0.7)
					(thickness 0.15)
				)
				(justify right top mirror)
			)
		)
		(pad "1" smd roundrect
			(at -0.7 0)
			(size 0.8 1)
			(layers "B.Cu" "B.Mask" "B.Paste")
			(roundrect_rratio 0.2)
			(net 289 "/Expansion connector/+12V_FMC")
			(pintype "passive")
		)
		(pad "2" smd roundrect
			(at 0.7 0)
			(size 0.8 1)
			(layers "B.Cu" "B.Mask" "B.Paste")
			(roundrect_rratio 0.2)
			(net 634 "+12V")
			(pintype "passive")
		)
	)
	(footprint "antmicro-footprints:TSOT23-6"
		(layer "B.Cu")
		(at 232.4 122)
		(property "Reference" "U18"
			(at -0.939999 1.947 0)
			(layer "B.SilkS")
			(effects
				(font
					(size 0.7 0.7)
					(thickness 0.15)
				)
				(justify right top mirror)
			)
		)
		(property "Value" "AP22615A_TSOT26"
			(at 0 -2.600001 0)
			(layer "B.Fab")
			(effects
				(font
					(size 0.7 0.7)
					(thickness 0.15)
				)
				(justify right top mirror)
			)
		)
		(property "Datasheet" "https://www.mouser.com/datasheet/2/115/DIOD_S_A0008958405_1-2543193.pdf"
			(at 0 0 0)
			(layer "B.Fab")
			(hide yes)
			(effects
				(font
					(size 1.27 1.27)
					(thickness 0.15)
				)
				(justify mirror)
			)
		)
		(property "Description" "Power Load Distribution Switch, High Side, Active High, 1 Output, 5.5 V, 3.6 A, 0.04 ohm, TSOT-26-6"
			(at 0 0 0)
			(layer "B.Fab")
			(hide yes)
			(effects
				(font
					(size 1.27 1.27)
					(thickness 0.15)
				)
				(justify mirror)
			)
		)
		(property "MPN" "AP22615AWU-7"
			(at 0 0 180)
			(unlocked yes)
			(layer "B.Fab")
			(hide yes)
			(effects
				(font
					(size 1 1)
					(thickness 0.15)
				)
				(justify mirror)
			)
		)
		(property "Manufacturer" "Diodes Incorporated"
			(at 0 0 180)
			(unlocked yes)
			(layer "B.Fab")
			(hide yes)
			(effects
				(font
					(size 1 1)
					(thickness 0.15)
				)
				(justify mirror)
			)
		)
		(property "Author" "Antmicro"
			(at 0 0 180)
			(unlocked yes)
			(layer "B.Fab")
			(hide yes)
			(effects
				(font
					(size 1 1)
					(thickness 0.15)
				)
				(justify mirror)
			)
		)
		(property "License" "Apache-2.0"
			(at 0 0 180)
			(unlocked yes)
			(layer "B.Fab")
			(hide yes)
			(effects
				(font
					(size 1 1)
					(thickness 0.15)
				)
				(justify mirror)
			)
		)
		(sheetname "/USB Hub/")
		(sheetfile "usb_hub.kicad_sch")
		(attr smd)
		(fp_line
			(start -1 -1.55)
			(end -1 -1.4)
			(stroke
				(width 0.15)
				(type solid)
			)
			(layer "B.SilkS")
		)
		(fp_line
			(start -1 1.5)
			(end -1 1.375)
			(stroke
				(width 0.15)
				(type solid)
			)
			(layer "B.SilkS")
		)
		(fp_line
			(start 1 -1.55)
			(end -1 -1.55)
			(stroke
				(width 0.15)
				(type solid)
			)
			(layer "B.SilkS")
		)
		(fp_line
			(start 1 -1.55)
			(end 1 -1.4)
			(stroke
				(width 0.15)
				(type solid)
			)
			(layer "B.SilkS")
		)
		(fp_line
			(start 1 1.497)
			(end -1 1.5)
			(stroke
				(width 0.15)
				(type solid)
			)
			(layer "B.SilkS")
		)
		(fp_line
			(start 1 1.497)
			(end 1 1.375)
			(stroke
				(width 0.15)
				(type solid)
			)
			(layer "B.SilkS")
		)
		(fp_circle
			(center -1.44 1.5)
			(end -1.39 1.5)
			(stroke
				(width 0.15)
				(type solid)
			)
			(fill yes)
			(layer "B.SilkS")
		)
		(fp_poly
			(pts
				(xy 1.930001 1.7) (xy 1.930001 -1.7) (xy -1.930001 -1.7) (xy -1.930001 1.7)
			)
			(stroke
				(width 0.05)
				(type solid)
			)
			(fill no)
			(layer "B.CrtYd")
		)
		(fp_line
			(start -0.45 1.520999)
			(end -0.876001 1.096)
			(stroke
				(width 0.15)
				(type solid)
			)
			(layer "B.Fab")
		)
		(fp_poly
			(pts
				(xy 0.875 -1.528) (xy 0.875 1.525) (xy -0.875 1.525) (xy -0.875 -1.528)
			)
			(stroke
				(width 0.15)
				(type solid)
			)
			(fill no)
			(layer "B.Fab")
		)
		(fp_text user "Author: Antmicro"
			(at -1.93 -5 0)
			(layer "B.Fab")
			(effects
				(font
					(size 0.7 0.7)
					(thickness 0.15)
				)
				(justify right top mirror)
			)
		)
		(fp_text user "License: Apache-2.0"
			(at -1.93 -6.199 0)
			(layer "B.Fab")
			(effects
				(font
					(size 0.7 0.7)
					(thickness 0.15)
				)
				(justify right top mirror)
			)
		)
		(fp_text user "${REFERENCE}"
			(at -1.93 -3.8 0)
			(layer "B.Fab")
			(effects
				(font
					(size 0.7 0.7)
					(thickness 0.15)
				)
				(justify right top mirror)
			)
		)
		(pad "1" smd rect
			(at -1.301 0.947 90)
			(size 0.7 1.2)
			(layers "B.Cu" "B.Mask" "B.Paste")
			(net 71 "/USB Hub/USBC3_VBUS")
			(pinfunction "OUT")
			(pintype "power_out")
		)
		(pad "2" smd rect
			(at -1.300999 -0.004 90)
			(size 0.7 1.2)
			(layers "B.Cu" "B.Mask" "B.Paste")
			(net 1 "GND")
			(pinfunction "GND")
			(pintype "power_in")
		)
		(pad "3" smd rect
			(at -1.301 -0.954 90)
			(size 0.7 1.2)
			(layers "B.Cu" "B.Mask" "B.Paste")
			(net 911 "/USB Hub/PRT_CTL2")
			(pinfunction "FLG")
			(pintype "output")
		)
		(pad "4" smd rect
			(at 1.299 -0.954 90)
			(size 0.7 1.2)
			(layers "B.Cu" "B.Mask" "B.Paste")
			(net 911 "/USB Hub/PRT_CTL2")
			(pinfunction "EN")
			(pintype "input")
		)
		(pad "5" smd rect
			(at 1.299 -0.004 90)
			(size 0.7 1.2)
			(layers "B.Cu" "B.Mask" "B.Paste")
			(net 909 "/USB Hub/USBC3_ISET")
			(pinfunction "ISET")
			(pintype "passive")
		)
		(pad "6" smd rect
			(at 1.299 0.947 90)
			(size 0.7 1.2)
			(layers "B.Cu" "B.Mask" "B.Paste")
			(net 5 "+5V")
			(pinfunction "IN")
			(pintype "power_in")
		)
	)
	(footprint "antmicro-footprints:R_0402_1005Metric"
		(layer "B.Cu")
		(at 220.18 109.51)
		(descr "Resistor SMD 0402")
		(tags "resistor SMD 0402")
		(property "Reference" "R299"
			(at -1.48 -1.41 0)
			(layer "B.SilkS")
			(effects
				(font
					(size 0.7 0.7)
					(thickness 0.15)
				)
				(justify right top mirror)
			)
		)
		(property "Value" "R_10k_0402"
			(at -1.011843 -1.772047 0)
			(layer "B.Fab")
			(effects
				(font
					(size 0.7 0.7)
					(thickness 0.15)
				)
				(justify right top mirror)
			)
		)
		(property "Datasheet" "https://www.bourns.com/docs/product-datasheets/cr.pdf"
			(at 0 0 0)
			(layer "B.Fab")
			(hide yes)
			(effects
				(font
					(size 1.27 1.27)
					(thickness 0.15)
				)
				(justify mirror)
			)
		)
		(property "Description" "SMD Chip Resistor, 10 kohm, ± 1%, 62.5 mW, 0402 [1005 Metric], Thick Film, General Purpose"
			(at 0 0 0)
			(layer "B.Fab")
			(hide yes)
			(effects
				(font
					(size 1.27 1.27)
					(thickness 0.15)
				)
				(justify mirror)
			)
		)
		(property "MPN" "CR0402-FX-1002GLF"
			(at 0 0 180)
			(unlocked yes)
			(layer "B.Fab")
			(hide yes)
			(effects
				(font
					(size 1 1)
					(thickness 0.15)
				)
				(justify mirror)
			)
		)
		(property "Manufacturer" "Bourns"
			(at 0 0 180)
			(unlocked yes)
			(layer "B.Fab")
			(hide yes)
			(effects
				(font
					(size 1 1)
					(thickness 0.15)
				)
				(justify mirror)
			)
		)
		(property "License" "Apache-2.0"
			(at 0 0 180)
			(unlocked yes)
			(layer "B.Fab")
			(hide yes)
			(effects
				(font
					(size 1 1)
					(thickness 0.15)
				)
				(justify mirror)
			)
		)
		(property "Author" "Antmicro"
			(at 0 0 180)
			(unlocked yes)
			(layer "B.Fab")
			(hide yes)
			(effects
				(font
					(size 1 1)
					(thickness 0.15)
				)
				(justify mirror)
			)
		)
		(property "Val" "10k"
			(at 0 0 180)
			(unlocked yes)
			(layer "B.Fab")
			(hide yes)
			(effects
				(font
					(size 1 1)
					(thickness 0.15)
				)
				(justify mirror)
			)
		)
		(property "Tolerance" "1%"
			(at 0 0 180)
			(unlocked yes)
			(layer "B.Fab")
			(hide yes)
			(effects
				(font
					(size 1 1)
					(thickness 0.15)
				)
				(justify mirror)
			)
		)
		(sheetname "/USB Hub/")
		(sheetfile "usb_hub.kicad_sch")
		(attr smd)
		(fp_rect
			(start -0.925 0.47)
			(end 0.925 -0.47)
			(stroke
				(width 0.05)
				(type default)
			)
			(fill no)
			(layer "B.CrtYd")
		)
		(fp_rect
			(start -0.5 0.25)
			(end 0.5 -0.25)
			(stroke
				(width 0.15)
				(type solid)
			)
			(fill no)
			(layer "B.Fab")
		)
		(fp_text user "${REFERENCE}"
			(at -0.95 -3.168 0)
			(layer "B.Fab")
			(effects
				(font
					(size 0.7 0.7)
					(thickness 0.15)
				)
				(justify right top mirror)
			)
		)
		(fp_text user "Author: Antmicro"
			(at -0.95 -4.169 0)
			(layer "B.Fab")
			(effects
				(font
					(size 0.7 0.7)
					(thickness 0.15)
				)
				(justify right top mirror)
			)
		)
		(fp_text user "License: Apache-2.0"
			(at -0.95 -5.169 0)
			(layer "B.Fab")
			(effects
				(font
					(size 0.7 0.7)
					(thickness 0.15)
				)
				(justify right top mirror)
			)
		)
		(pad "1" smd roundrect
			(at -0.48 0)
			(size 0.59 0.64)
			(layers "B.Cu" "B.Mask" "B.Paste")
			(roundrect_rratio 0.25)
			(net 5 "+5V")
			(pintype "passive")
		)
		(pad "2" smd roundrect
			(at 0.48 0)
			(size 0.59 0.64)
			(layers "B.Cu" "B.Mask" "B.Paste")
			(roundrect_rratio 0.25)
			(net 1330 "Net-(Q21-D1)")
			(pintype "passive")
		)
	)
	(footprint "antmicro-footprints:TP_SMD_0.75mm"
		(layer "B.Cu")
		(at 155.5 113 -90)
		(property "Reference" "TP87"
			(at 0 0.6 90)
			(layer "B.SilkS")
			(effects
				(font
					(size 0.7 0.7)
					(thickness 0.15)
				)
				(justify left bottom mirror)
			)
		)
		(property "Value" "TP_0.75mm_SMD"
			(at 0 -1.2 90)
			(layer "B.Fab")
			(effects
				(font
					(size 0.7 0.7)
					(thickness 0.15)
				)
				(justify left bottom mirror)
			)
		)
		(property "Description" "SMT test point"
			(at 0 0 90)
			(layer "B.Fab")
			(hide yes)
			(effects
				(font
					(size 1.27 1.27)
					(thickness 0.15)
				)
				(justify mirror)
			)
		)
		(property "MPN" ""
			(at 0 0 90)
			(unlocked yes)
			(layer "B.Fab")
			(hide yes)
			(effects
				(font
					(size 1 1)
					(thickness 0.15)
				)
				(justify mirror)
			)
		)
		(property "Manufacturer" ""
			(at 0 0 90)
			(unlocked yes)
			(layer "B.Fab")
			(hide yes)
			(effects
				(font
					(size 1 1)
					(thickness 0.15)
				)
				(justify mirror)
			)
		)
		(property "Author" "Antmicro"
			(at 0 0 90)
			(unlocked yes)
			(layer "B.Fab")
			(hide yes)
			(effects
				(font
					(size 1 1)
					(thickness 0.15)
				)
				(justify mirror)
			)
		)
		(property "License" "Apache-2.0"
			(at 0 0 90)
			(unlocked yes)
			(layer "B.Fab")
			(hide yes)
			(effects
				(font
					(size 1 1)
					(thickness 0.15)
				)
				(justify mirror)
			)
		)
		(sheetname "/Peripherals/")
		(sheetfile "peripherals.kicad_sch")
		(attr exclude_from_pos_files exclude_from_bom)
		(fp_circle
			(center 0 0)
			(end 0.475 0)
			(stroke
				(width 0.05)
				(type default)
			)
			(fill no)
			(layer "B.CrtYd")
		)
		(fp_text user "License: Apache-2.0"
			(at -0.4 -5.101 90)
			(layer "B.Fab")
			(effects
				(font
					(size 0.7 0.7)
					(thickness 0.15)
				)
				(justify left bottom mirror)
			)
		)
		(fp_text user "Author: Antmicro"
			(at -0.4 -3.901 90)
			(layer "B.Fab")
			(effects
				(font
					(size 0.7 0.7)
					(thickness 0.15)
				)
				(justify left bottom mirror)
			)
		)
		(fp_text user "${REFERENCE}"
			(at -0.4 -2.7 90)
			(layer "B.Fab")
			(effects
				(font
					(size 0.7 0.7)
					(thickness 0.15)
				)
				(justify left bottom mirror)
			)
		)
		(pad "1" smd circle
			(at 0 0 270)
			(size 0.75 0.75)
			(layers "B.Cu" "B.Mask")
			(net 850 "/I2C_{SYS}.SDA")
			(pinfunction "1")
			(pintype "passive")
		)
	)
)
